(kicad_pcb
	(version 20260206)
	(generator "pcbnew")
	(generator_version "10.0")
	(general
		(thickness 1.6)
		(legacy_teardrops no)
	)
	(paper "A4")
	(title_block
		(title "03242023_DA0F0TMBIJ0_F0T_Motherboard_J_brd_V01_OCP.brd")
		(comment 1 "Grand Teton / footprints 5627-5632 of 6105")
	)
	(layers
		(0 "F.Cu" signal "TOP")
		(4 "In1.Cu" signal "GND")
		(6 "In2.Cu" signal "IN1")
		(8 "In3.Cu" signal "GND1")
		(10 "In4.Cu" signal "IN2")
		(12 "In5.Cu" signal "GND2")
		(14 "In6.Cu" signal "IN3")
		(16 "In7.Cu" signal "GND3")
		(18 "In8.Cu" signal "VCC")
		(20 "In9.Cu" signal "VCC1")
		(22 "In10.Cu" signal "GND4")
		(24 "In11.Cu" signal "IN4")
		(26 "In12.Cu" signal "GND5")
		(28 "In13.Cu" signal "IN5")
		(30 "In14.Cu" signal "GND6")
		(32 "In15.Cu" signal "IN6")
		(34 "In16.Cu" signal "GND7")
		(2 "B.Cu" signal "BOTTOM")
		(9 "F.Adhes" user "F.Adhesive")
		(11 "B.Adhes" user "B.Adhesive")
		(13 "F.Paste" user "Package Geometry/Pastemask Top")
		(15 "B.Paste" user "Package Geometry/Pastemask Bottom")
		(5 "F.SilkS" user "Ref Des/Silkscreen Top")
		(7 "B.SilkS" user "Ref Des/Silkscreen Bottom")
		(1 "F.Mask" user "Board Geometry/Soldermask Top")
		(3 "B.Mask" user "Board Geometry/Soldermask Bottom")
		(17 "Dwgs.User" user "User.Drawings")
		(19 "Cmts.User" user "User.Comments")
		(21 "Eco1.User" user "User.Eco1")
		(23 "Eco2.User" user "User.Eco2")
		(25 "Edge.Cuts" user "Board Geometry/Outline")
		(27 "Margin" user)
		(31 "F.CrtYd" user "Package Geometry/Place Bound Top")
		(29 "B.CrtYd" user "Package Geometry/Place Bound Bottom")
		(35 "F.Fab" user "Ref Des/Assembly Top")
		(33 "B.Fab" user "Ref Des/Assembly Bottom")
	)
	(footprint ""
		(layer "B.Cu")
		(at 415.271712 -193.08953 -90)
		(property "Reference" "R319"
			(at 0 0 90)
			(layer "B.SilkS")
			(hide yes)
			(effects
				(font
					(size 1.27 1.27)
				)
				(justify mirror)
			)
		)
		(property "Value" ""
			(at 0 0 90)
			(layer "B.Fab")
			(effects
				(font
					(size 1.27 1.27)
				)
				(justify mirror)
			)
		)
		(duplicate_pad_numbers_are_jumpers no)
		(fp_line
			(start -0.7874 0.4064)
			(end 0.7874 0.4064)
			(stroke
				(width 0.1524)
				(type default)
			)
			(layer "B.SilkS")
		)
		(fp_line
			(start 0.7874 0.4064)
			(end 0.7874 -0.4064)
			(stroke
				(width 0.1524)
				(type default)
			)
			(layer "B.SilkS")
		)
		(fp_line
			(start -0.7874 -0.4064)
			(end -0.7874 0.4064)
			(stroke
				(width 0.1524)
				(type default)
			)
			(layer "B.SilkS")
		)
		(fp_line
			(start 0.7874 -0.4064)
			(end -0.7874 -0.4064)
			(stroke
				(width 0.1524)
				(type default)
			)
			(layer "B.SilkS")
		)
		(fp_line
			(start -0.67945 0.3048)
			(end -0.120396 0.3048)
			(stroke
				(width 0.1)
				(type default)
			)
			(layer "B.Fab")
		)
		(fp_line
			(start -0.120396 0.3048)
			(end -0.120396 0.2794)
			(stroke
				(width 0.1)
				(type default)
			)
			(layer "B.Fab")
		)
		(fp_line
			(start 0.12065 0.3048)
			(end 0.67945 0.3048)
			(stroke
				(width 0.1)
				(type default)
			)
			(layer "B.Fab")
		)
		(fp_line
			(start 0.67945 0.3048)
			(end 0.67945 -0.305054)
			(stroke
				(width 0.1)
				(type default)
			)
			(layer "B.Fab")
		)
		(fp_line
			(start -0.120396 0.2794)
			(end 0.12065 0.2794)
			(stroke
				(width 0.1)
				(type default)
			)
			(layer "B.Fab")
		)
		(fp_line
			(start 0.12065 0.2794)
			(end 0.12065 0.3048)
			(stroke
				(width 0.1)
				(type default)
			)
			(layer "B.Fab")
		)
		(fp_line
			(start -0.12065 -0.2794)
			(end -0.12065 -0.3048)
			(stroke
				(width 0.1)
				(type default)
			)
			(layer "B.Fab")
		)
		(fp_line
			(start 0.12065 -0.2794)
			(end -0.12065 -0.2794)
			(stroke
				(width 0.1)
				(type default)
			)
			(layer "B.Fab")
		)
		(fp_line
			(start -0.67945 -0.3048)
			(end -0.67945 0.3048)
			(stroke
				(width 0.1)
				(type default)
			)
			(layer "B.Fab")
		)
		(fp_line
			(start -0.12065 -0.3048)
			(end -0.67945 -0.3048)
			(stroke
				(width 0.1)
				(type default)
			)
			(layer "B.Fab")
		)
		(fp_line
			(start 0.12065 -0.305054)
			(end 0.12065 -0.2794)
			(stroke
				(width 0.1)
				(type default)
			)
			(layer "B.Fab")
		)
		(fp_line
			(start 0.67945 -0.305054)
			(end 0.12065 -0.305054)
			(stroke
				(width 0.1)
				(type default)
			)
			(layer "B.Fab")
		)
		(pad "1" smd circle
			(at 0.40005 0 90)
			(size 0 0)
			(layers "B.Cu" "B.Mask" "B.Paste")
			(net "P3V3_AUX")
		)
		(pad "2" smd circle
			(at -0.40005 0 90)
			(size 0 0)
			(layers "B.Cu" "B.Mask" "B.Paste")
			(net "PU_S3M_CPU0_CPLD_STATUS")
		)
	)
	(footprint ""
		(layer "B.Cu")
		(at 366.120934 -244.820186 -90)
		(property "Reference" "C382"
			(at 0 0 90)
			(layer "B.SilkS")
			(hide yes)
			(effects
				(font
					(size 1.27 1.27)
				)
				(justify mirror)
			)
		)
		(property "Value" ""
			(at 0 0 90)
			(layer "B.Fab")
			(effects
				(font
					(size 1.27 1.27)
				)
				(justify mirror)
			)
		)
		(duplicate_pad_numbers_are_jumpers no)
		(fp_line
			(start -1.524 0.762)
			(end 1.524 0.762)
			(stroke
				(width 0.1524)
				(type default)
			)
			(layer "B.SilkS")
		)
		(fp_line
			(start 1.524 0.762)
			(end 1.524 -0.762)
			(stroke
				(width 0.1524)
				(type default)
			)
			(layer "B.SilkS")
		)
		(fp_line
			(start -1.524 -0.762)
			(end -1.524 0.762)
			(stroke
				(width 0.1524)
				(type default)
			)
			(layer "B.SilkS")
		)
		(fp_line
			(start 1.524 -0.762)
			(end -1.524 -0.762)
			(stroke
				(width 0.1524)
				(type default)
			)
			(layer "B.SilkS")
		)
		(fp_line
			(start -1.1049 0.724916)
			(end -1.1049 -0.724916)
			(stroke
				(width 0.1)
				(type default)
			)
			(layer "B.Fab")
		)
		(fp_line
			(start 1.1049 0.724916)
			(end -1.1049 0.724916)
			(stroke
				(width 0.1)
				(type default)
			)
			(layer "B.Fab")
		)
		(fp_line
			(start -1.1049 -0.724916)
			(end 1.1049 -0.724916)
			(stroke
				(width 0.1)
				(type default)
			)
			(layer "B.Fab")
		)
		(fp_line
			(start 1.1049 -0.724916)
			(end 1.1049 0.724916)
			(stroke
				(width 0.1)
				(type default)
			)
			(layer "B.Fab")
		)
		(pad "1" smd rect
			(at 0.889 0 270)
			(size 1.016 1.27)
			(layers "B.Cu" "B.Mask" "B.Paste")
			(net "PVCCIN_CPU0")
		)
		(pad "2" smd rect
			(at -0.889 0 270)
			(size 1.016 1.27)
			(layers "B.Cu" "B.Mask" "B.Paste")
			(net "GND")
		)
	)
	(footprint ""
		(layer "B.Cu")
		(at 298.626784 -356.036372 -90)
		(property "Reference" "PC2170"
			(at 0 0 90)
			(layer "B.SilkS")
			(hide yes)
			(effects
				(font
					(size 1.27 1.27)
				)
				(justify mirror)
			)
		)
		(property "Value" ""
			(at 0 0 90)
			(layer "B.Fab")
			(effects
				(font
					(size 1.27 1.27)
				)
				(justify mirror)
			)
		)
		(duplicate_pad_numbers_are_jumpers no)
		(fp_line
			(start -4.533392 2.249932)
			(end 4.533392 2.249932)
			(stroke
				(width 0.1524)
				(type default)
			)
			(layer "B.SilkS")
		)
		(fp_line
			(start 4.533392 2.249932)
			(end 4.533392 -2.249932)
			(stroke
				(width 0.1524)
				(type default)
			)
			(layer "B.SilkS")
		)
		(fp_line
			(start -4.533392 -2.249932)
			(end -4.533392 2.249932)
			(stroke
				(width 0.1524)
				(type default)
			)
			(layer "B.SilkS")
		)
		(fp_line
			(start 4.533392 -2.249932)
			(end -4.533392 -2.249932)
			(stroke
				(width 0.1524)
				(type default)
			)
			(layer "B.SilkS")
		)
		(fp_poly
			(pts
				(xy 4.533392 -2.326132) (xy 5.39242 -2.326132) (xy 5.39242 2.326132) (xy 4.533392 2.326132)
			)
			(stroke
				(width 0)
				(type default)
			)
			(fill yes)
			(layer "B.SilkS")
		)
		(fp_line
			(start -3.750056 2.249932)
			(end 3.750056 2.249932)
			(stroke
				(width 0.1)
				(type default)
			)
			(layer "B.Fab")
		)
		(fp_line
			(start 3.750056 2.249932)
			(end 3.750056 -2.249932)
			(stroke
				(width 0.1)
				(type default)
			)
			(layer "B.Fab")
		)
		(fp_line
			(start -3.750056 -2.249932)
			(end -3.750056 2.249932)
			(stroke
				(width 0.1)
				(type default)
			)
			(layer "B.Fab")
		)
		(fp_line
			(start 3.750056 -2.249932)
			(end -3.750056 -2.249932)
			(stroke
				(width 0.1)
				(type default)
			)
			(layer "B.Fab")
		)
		(fp_text user "+"
			(at 6.322314 0.786384 180)
			(unlocked yes)
			(layer "B.SilkS")
			(effects
				(font
					(size 1.905 1.4224)
					(thickness 0.1524)
				)
				(justify left mirror)
			)
		)
		(fp_text user "-"
			(at -4.8514 -0.14605 270)
			(unlocked yes)
			(layer "B.SilkS")
			(effects
				(font
					(size 1.905 1.4224)
					(thickness 0.1524)
				)
				(justify left mirror)
			)
		)
		(fp_text user "+"
			(at 6.322314 0.786384 180)
			(unlocked yes)
			(layer "B.Fab")
			(effects
				(font
					(size 1.905 1.4224)
					(thickness 0.1524)
				)
				(justify left mirror)
			)
		)
		(fp_text user "-"
			(at -4.8514 -0.14605 270)
			(unlocked yes)
			(layer "B.Fab")
			(effects
				(font
					(size 1.905 1.4224)
					(thickness 0.1524)
				)
				(justify left mirror)
			)
		)
		(pad "1" smd rect
			(at 3.199892 0 90)
			(size 2.413 2.8194)
			(layers "B.Cu" "B.Mask" "B.Paste")
			(net "PVCCFA_EHV_FIVRA_CPU0")
		)
		(pad "2" smd rect
			(at -3.199892 0 90)
			(size 2.413 2.8194)
			(layers "B.Cu" "B.Mask" "B.Paste")
			(net "GND")
		)
	)
	(footprint ""
		(layer "B.Cu")
		(at 10.558272 -184.625996)
		(property "Reference" "R966"
			(at 0 0 0)
			(layer "B.SilkS")
			(hide yes)
			(effects
				(font
					(size 1.27 1.27)
				)
				(justify mirror)
			)
		)
		(property "Value" ""
			(at 0 0 0)
			(layer "B.Fab")
			(effects
				(font
					(size 1.27 1.27)
				)
				(justify mirror)
			)
		)
		(duplicate_pad_numbers_are_jumpers no)
		(fp_line
			(start -0.7874 -0.4064)
			(end -0.7874 0.4064)
			(stroke
				(width 0.1524)
				(type default)
			)
			(layer "B.SilkS")
		)
		(fp_line
			(start -0.7874 0.4064)
			(end 0.7874 0.4064)
			(stroke
				(width 0.1524)
				(type default)
			)
			(layer "B.SilkS")
		)
		(fp_line
			(start 0.7874 -0.4064)
			(end -0.7874 -0.4064)
			(stroke
				(width 0.1524)
				(type default)
			)
			(layer "B.SilkS")
		)
		(fp_line
			(start 0.7874 0.4064)
			(end 0.7874 -0.4064)
			(stroke
				(width 0.1524)
				(type default)
			)
			(layer "B.SilkS")
		)
		(fp_line
			(start -0.67945 -0.3048)
			(end -0.67945 0.3048)
			(stroke
				(width 0.1)
				(type default)
			)
			(layer "B.Fab")
		)
		(fp_line
			(start -0.67945 0.3048)
			(end -0.120396 0.3048)
			(stroke
				(width 0.1)
				(type default)
			)
			(layer "B.Fab")
		)
		(fp_line
			(start -0.12065 -0.3048)
			(end -0.67945 -0.3048)
			(stroke
				(width 0.1)
				(type default)
			)
			(layer "B.Fab")
		)
		(fp_line
			(start -0.12065 -0.2794)
			(end -0.12065 -0.3048)
			(stroke
				(width 0.1)
				(type default)
			)
			(layer "B.Fab")
		)
		(fp_line
			(start -0.120396 0.2794)
			(end 0.12065 0.2794)
			(stroke
				(width 0.1)
				(type default)
			)
			(layer "B.Fab")
		)
		(fp_line
			(start -0.120396 0.3048)
			(end -0.120396 0.2794)
			(stroke
				(width 0.1)
				(type default)
			)
			(layer "B.Fab")
		)
		(fp_line
			(start 0.12065 -0.305054)
			(end 0.12065 -0.2794)
			(stroke
				(width 0.1)
				(type default)
			)
			(layer "B.Fab")
		)
		(fp_line
			(start 0.12065 -0.2794)
			(end -0.12065 -0.2794)
			(stroke
				(width 0.1)
				(type default)
			)
			(layer "B.Fab")
		)
		(fp_line
			(start 0.12065 0.2794)
			(end 0.12065 0.3048)
			(stroke
				(width 0.1)
				(type default)
			)
			(layer "B.Fab")
		)
		(fp_line
			(start 0.12065 0.3048)
			(end 0.67945 0.3048)
			(stroke
				(width 0.1)
				(type default)
			)
			(layer "B.Fab")
		)
		(fp_line
			(start 0.67945 -0.305054)
			(end 0.12065 -0.305054)
			(stroke
				(width 0.1)
				(type default)
			)
			(layer "B.Fab")
		)
		(fp_line
			(start 0.67945 0.3048)
			(end 0.67945 -0.305054)
			(stroke
				(width 0.1)
				(type default)
			)
			(layer "B.Fab")
		)
		(pad "1" smd circle
			(at 0.40005 0 180)
			(size 0 0)
			(layers "B.Cu" "B.Mask" "B.Paste")
			(net "P3V3_AUX")
		)
		(pad "2" smd circle
			(at -0.40005 0 180)
			(size 0 0)
			(layers "B.Cu" "B.Mask" "B.Paste")
			(net "SMB_PEHPCPU1_LVC3_SCL")
		)
	)
	(footprint ""
		(layer "B.Cu")
		(at 70.369684 -188.458856 90)
		(property "Reference" "R55"
			(at 0 0 90)
			(layer "B.SilkS")
			(hide yes)
			(effects
				(font
					(size 1.27 1.27)
				)
				(justify mirror)
			)
		)
		(property "Value" ""
			(at 0 0 90)
			(layer "B.Fab")
			(effects
				(font
					(size 1.27 1.27)
				)
				(justify mirror)
			)
		)
		(duplicate_pad_numbers_are_jumpers no)
		(fp_line
			(start 0.7874 -0.4064)
			(end -0.7874 -0.4064)
			(stroke
				(width 0.1524)
				(type default)
			)
			(layer "B.SilkS")
		)
		(fp_line
			(start -0.7874 -0.4064)
			(end -0.7874 0.4064)
			(stroke
				(width 0.1524)
				(type default)
			)
			(layer "B.SilkS")
		)
		(fp_line
			(start 0.7874 0.4064)
			(end 0.7874 -0.4064)
			(stroke
				(width 0.1524)
				(type default)
			)
			(layer "B.SilkS")
		)
		(fp_line
			(start -0.7874 0.4064)
			(end 0.7874 0.4064)
			(stroke
				(width 0.1524)
				(type default)
			)
			(layer "B.SilkS")
		)
		(fp_line
			(start 0.67945 -0.305054)
			(end 0.12065 -0.305054)
			(stroke
				(width 0.1)
				(type default)
			)
			(layer "B.Fab")
		)
		(fp_line
			(start 0.12065 -0.305054)
			(end 0.12065 -0.2794)
			(stroke
				(width 0.1)
				(type default)
			)
			(layer "B.Fab")
		)
		(fp_line
			(start -0.12065 -0.3048)
			(end -0.67945 -0.3048)
			(stroke
				(width 0.1)
				(type default)
			)
			(layer "B.Fab")
		)
		(fp_line
			(start -0.67945 -0.3048)
			(end -0.67945 0.3048)
			(stroke
				(width 0.1)
				(type default)
			)
			(layer "B.Fab")
		)
		(fp_line
			(start 0.12065 -0.2794)
			(end -0.12065 -0.2794)
			(stroke
				(width 0.1)
				(type default)
			)
			(layer "B.Fab")
		)
		(fp_line
			(start -0.12065 -0.2794)
			(end -0.12065 -0.3048)
			(stroke
				(width 0.1)
				(type default)
			)
			(layer "B.Fab")
		)
		(fp_line
			(start 0.12065 0.2794)
			(end 0.12065 0.3048)
			(stroke
				(width 0.1)
				(type default)
			)
			(layer "B.Fab")
		)
		(fp_line
			(start -0.120396 0.2794)
			(end 0.12065 0.2794)
			(stroke
				(width 0.1)
				(type default)
			)
			(layer "B.Fab")
		)
		(fp_line
			(start 0.67945 0.3048)
			(end 0.67945 -0.305054)
			(stroke
				(width 0.1)
				(type default)
			)
			(layer "B.Fab")
		)
		(fp_line
			(start 0.12065 0.3048)
			(end 0.67945 0.3048)
			(stroke
				(width 0.1)
				(type default)
			)
			(layer "B.Fab")
		)
		(fp_line
			(start -0.120396 0.3048)
			(end -0.120396 0.2794)
			(stroke
				(width 0.1)
				(type default)
			)
			(layer "B.Fab")
		)
		(fp_line
			(start -0.67945 0.3048)
			(end -0.120396 0.3048)
			(stroke
				(width 0.1)
				(type default)
			)
			(layer "B.Fab")
		)
		(pad "1" smd circle
			(at 0.40005 0 270)
			(size 0 0)
			(layers "B.Cu" "B.Mask" "B.Paste")
			(net "SVID_DIO0_CPU1")
		)
		(pad "2" smd circle
			(at -0.40005 0 270)
			(size 0 0)
			(layers "B.Cu" "B.Mask" "B.Paste")
			(net "SVID_DIO0_CPU1_R")
		)
	)
	(footprint ""
		(layer "B.Cu")
		(at 332.543912 -31.386272 90)
		(property "Reference" "R1395"
			(at 0 0 90)
			(layer "B.SilkS")
			(hide yes)
			(effects
				(font
					(size 1.27 1.27)
				)
				(justify mirror)
			)
		)
		(property "Value" ""
			(at 0 0 90)
			(layer "B.Fab")
			(effects
				(font
					(size 1.27 1.27)
				)
				(justify mirror)
			)
		)
		(duplicate_pad_numbers_are_jumpers no)
		(fp_line
			(start 0.7874 -0.4064)
			(end -0.7874 -0.4064)
			(stroke
				(width 0.1524)
				(type default)
			)
			(layer "B.SilkS")
		)
		(fp_line
			(start -0.7874 -0.4064)
			(end -0.7874 0.4064)
			(stroke
				(width 0.1524)
				(type default)
			)
			(layer "B.SilkS")
		)
		(fp_line
			(start 0.7874 0.4064)
			(end 0.7874 -0.4064)
			(stroke
				(width 0.1524)
				(type default)
			)
			(layer "B.SilkS")
		)
		(fp_line
			(start -0.7874 0.4064)
			(end 0.7874 0.4064)
			(stroke
				(width 0.1524)
				(type default)
			)
			(layer "B.SilkS")
		)
		(fp_line
			(start 0.67945 -0.305054)
			(end 0.12065 -0.305054)
			(stroke
				(width 0.1)
				(type default)
			)
			(layer "B.Fab")
		)
		(fp_line
			(start 0.12065 -0.305054)
			(end 0.12065 -0.2794)
			(stroke
				(width 0.1)
				(type default)
			)
			(layer "B.Fab")
		)
		(fp_line
			(start -0.12065 -0.3048)
			(end -0.67945 -0.3048)
			(stroke
				(width 0.1)
				(type default)
			)
			(layer "B.Fab")
		)
		(fp_line
			(start -0.67945 -0.3048)
			(end -0.67945 0.3048)
			(stroke
				(width 0.1)
				(type default)
			)
			(layer "B.Fab")
		)
		(fp_line
			(start 0.12065 -0.2794)
			(end -0.12065 -0.2794)
			(stroke
				(width 0.1)
				(type default)
			)
			(layer "B.Fab")
		)
		(fp_line
			(start -0.12065 -0.2794)
			(end -0.12065 -0.3048)
			(stroke
				(width 0.1)
				(type default)
			)
			(layer "B.Fab")
		)
		(fp_line
			(start 0.12065 0.2794)
			(end 0.12065 0.3048)
			(stroke
				(width 0.1)
				(type default)
			)
			(layer "B.Fab")
		)
		(fp_line
			(start -0.120396 0.2794)
			(end 0.12065 0.2794)
			(stroke
				(width 0.1)
				(type default)
			)
			(layer "B.Fab")
		)
		(fp_line
			(start 0.67945 0.3048)
			(end 0.67945 -0.305054)
			(stroke
				(width 0.1)
				(type default)
			)
			(layer "B.Fab")
		)
		(fp_line
			(start 0.12065 0.3048)
			(end 0.67945 0.3048)
			(stroke
				(width 0.1)
				(type default)
			)
			(layer "B.Fab")
		)
		(fp_line
			(start -0.120396 0.3048)
			(end -0.120396 0.2794)
			(stroke
				(width 0.1)
				(type default)
			)
			(layer "B.Fab")
		)
		(fp_line
			(start -0.67945 0.3048)
			(end -0.120396 0.3048)
			(stroke
				(width 0.1)
				(type default)
			)
			(layer "B.Fab")
		)
		(pad "1" smd circle
			(at 0.40005 0 270)
			(size 0 0)
			(layers "B.Cu" "B.Mask" "B.Paste")
			(net "SPI_PCH_TPM_CS_N")
		)
		(pad "2" smd circle
			(at -0.40005 0 270)
			(size 0 0)
			(layers "B.Cu" "B.Mask" "B.Paste")
			(net "SPI_TPM_CS_N")
		)
	)
)
